# T6G (Grand Teton) — schematic netlist excerpt (pin names and nets, part order shuffled) for the footprints in the layout excerpt that follows; sources: Cadence DE-HDL packaged netlist, KiCad conversion of 04192023_DAF0TMB3IC0_F0TG_MB_C_brd_V02_OCP.brd

R1455  Q_RES  4.7K 5% EMPTY  pkg 0201LF  page 331 : A = P1V8_CPU1_RT_1D ; B = JTAG_TMS_RT_CPU1_P1
R1553  Q_RES  33 5% CHIP  pkg 0402LF  page 81 : A = ESPI_CPU0_CS1_R_N ; B = ESPI_CPU0_CS1_N
R4560  Q_RES  4.7K 5% CHIP  pkg 0402LF  page 125 : A = P3V3_AUX ; B = SWB_HSC_PWRGD_N

(kicad_pcb
	(version 20260206)
	(generator "pcbnew")
	(generator_version "10.0")
	(general
		(thickness 1.6)
		(legacy_teardrops no)
	)
	(paper "A4")
	(title_block
		(title "04192023_DAF0TMB3IC0_F0TG_MB_C_brd_V02_OCP.brd")
		(comment 1 "Grand Teton / footprints 1674-1676 of 8354")
	)
	(layers
		(0 "F.Cu" signal "TOP")
		(4 "In1.Cu" signal "GND")
		(6 "In2.Cu" signal "IN1")
		(8 "In3.Cu" signal "GND1")
		(10 "In4.Cu" signal "IN2")
		(12 "In5.Cu" signal "GND2")
		(14 "In6.Cu" signal "IN3")
		(16 "In7.Cu" signal "GND3")
		(18 "In8.Cu" signal "VCC")
		(20 "In9.Cu" signal "VCC1")
		(22 "In10.Cu" signal "GND4")
		(24 "In11.Cu" signal "IN4")
		(26 "In12.Cu" signal "GND5")
		(28 "In13.Cu" signal "IN5")
		(30 "In14.Cu" signal "GND6")
		(32 "In15.Cu" signal "IN6")
		(34 "In16.Cu" signal "GND7")
		(2 "B.Cu" signal "BOTTOM")
		(9 "F.Adhes" user "F.Adhesive")
		(11 "B.Adhes" user "B.Adhesive")
		(13 "F.Paste" user "Package Geometry/Pastemask Top")
		(15 "B.Paste" user "Package Geometry/Pastemask Bottom")
		(5 "F.SilkS" user "Ref Des/Silkscreen Top")
		(7 "B.SilkS" user "Ref Des/Silkscreen Bottom")
		(1 "F.Mask" user "Board Geometry/Soldermask Top")
		(3 "B.Mask" user "Board Geometry/Soldermask Bottom")
		(17 "Dwgs.User" user "User.Drawings")
		(19 "Cmts.User" user "User.Comments")
		(21 "Eco1.User" user "User.Eco1")
		(23 "Eco2.User" user "User.Eco2")
		(25 "Edge.Cuts" user "Board Geometry/Outline")
		(27 "Margin" user)
		(31 "F.CrtYd" user "Package Geometry/Place Bound Top")
		(29 "B.CrtYd" user "Package Geometry/Place Bound Bottom")
		(35 "F.Fab" user "Ref Des/Assembly Top")
		(33 "B.Fab" user "Ref Des/Assembly Bottom")
	)
	(footprint ""
		(layer "F.Cu")
		(at 353.10445 -430.590452 180)
		(property "Reference" "R4560"
			(at 0 0 180)
			(layer "F.SilkS")
			(hide yes)
			(effects
				(font
					(size 1.27 1.27)
				)
			)
		)
		(property "Value" ""
			(at 0 0 180)
			(layer "F.Fab")
			(effects
				(font
					(size 1.27 1.27)
				)
			)
		)
		(duplicate_pad_numbers_are_jumpers no)
		(fp_line
			(start 0.7874 0.4064)
			(end -0.7874 0.4064)
			(stroke
				(width 0.1524)
				(type default)
			)
			(layer "F.SilkS")
		)
		(fp_line
			(start 0.7874 -0.4064)
			(end 0.7874 0.4064)
			(stroke
				(width 0.1524)
				(type default)
			)
			(layer "F.SilkS")
		)
		(fp_line
			(start -0.7874 0.4064)
			(end -0.7874 -0.4064)
			(stroke
				(width 0.1524)
				(type default)
			)
			(layer "F.SilkS")
		)
		(fp_line
			(start -0.7874 -0.4064)
			(end 0.7874 -0.4064)
			(stroke
				(width 0.1524)
				(type default)
			)
			(layer "F.SilkS")
		)
		(fp_line
			(start 0.67945 0.3048)
			(end 0.120396 0.3048)
			(stroke
				(width 0.1)
				(type default)
			)
			(layer "F.Fab")
		)
		(fp_line
			(start 0.67945 -0.3048)
			(end 0.67945 0.3048)
			(stroke
				(width 0.1)
				(type default)
			)
			(layer "F.Fab")
		)
		(fp_line
			(start 0.12065 -0.2794)
			(end 0.12065 -0.3048)
			(stroke
				(width 0.1)
				(type default)
			)
			(layer "F.Fab")
		)
		(fp_line
			(start 0.12065 -0.3048)
			(end 0.67945 -0.3048)
			(stroke
				(width 0.1)
				(type default)
			)
			(layer "F.Fab")
		)
		(fp_line
			(start 0.120396 0.3048)
			(end 0.120396 0.2794)
			(stroke
				(width 0.1)
				(type default)
			)
			(layer "F.Fab")
		)
		(fp_line
			(start 0.120396 0.2794)
			(end -0.12065 0.2794)
			(stroke
				(width 0.1)
				(type default)
			)
			(layer "F.Fab")
		)
		(fp_line
			(start -0.12065 0.3048)
			(end -0.67945 0.3048)
			(stroke
				(width 0.1)
				(type default)
			)
			(layer "F.Fab")
		)
		(fp_line
			(start -0.12065 0.2794)
			(end -0.12065 0.3048)
			(stroke
				(width 0.1)
				(type default)
			)
			(layer "F.Fab")
		)
		(fp_line
			(start -0.12065 -0.2794)
			(end 0.12065 -0.2794)
			(stroke
				(width 0.1)
				(type default)
			)
			(layer "F.Fab")
		)
		(fp_line
			(start -0.12065 -0.305054)
			(end -0.12065 -0.2794)
			(stroke
				(width 0.1)
				(type default)
			)
			(layer "F.Fab")
		)
		(fp_line
			(start -0.67945 0.3048)
			(end -0.67945 -0.305054)
			(stroke
				(width 0.1)
				(type default)
			)
			(layer "F.Fab")
		)
		(fp_line
			(start -0.67945 -0.305054)
			(end -0.12065 -0.305054)
			(stroke
				(width 0.1)
				(type default)
			)
			(layer "F.Fab")
		)
		(pad "1" smd circle
			(at -0.40005 0 180)
			(size 0 0)
			(layers "F.Cu" "F.Mask" "F.Paste")
			(net "P3V3_AUX")
		)
		(pad "2" smd circle
			(at 0.40005 0 180)
			(size 0 0)
			(layers "F.Cu" "F.Mask" "F.Paste")
			(net "SWB_HSC_PWRGD_N")
		)
	)
	(footprint ""
		(layer "F.Cu")
		(at 188.18733 -133.573774 90)
		(property "Reference" "R1553"
			(at 0 0 90)
			(layer "F.SilkS")
			(hide yes)
			(effects
				(font
					(size 1.27 1.27)
				)
			)
		)
		(property "Value" ""
			(at 0 0 90)
			(layer "F.Fab")
			(effects
				(font
					(size 1.27 1.27)
				)
			)
		)
		(duplicate_pad_numbers_are_jumpers no)
		(fp_line
			(start 0.7874 -0.4064)
			(end 0.7874 0.4064)
			(stroke
				(width 0.1524)
				(type default)
			)
			(layer "F.SilkS")
		)
		(fp_line
			(start -0.7874 -0.4064)
			(end 0.7874 -0.4064)
			(stroke
				(width 0.1524)
				(type default)
			)
			(layer "F.SilkS")
		)
		(fp_line
			(start 0.7874 0.4064)
			(end -0.7874 0.4064)
			(stroke
				(width 0.1524)
				(type default)
			)
			(layer "F.SilkS")
		)
		(fp_line
			(start -0.7874 0.4064)
			(end -0.7874 -0.4064)
			(stroke
				(width 0.1524)
				(type default)
			)
			(layer "F.SilkS")
		)
		(fp_line
			(start -0.12065 -0.305054)
			(end -0.12065 -0.2794)
			(stroke
				(width 0.1)
				(type default)
			)
			(layer "F.Fab")
		)
		(fp_line
			(start -0.67945 -0.305054)
			(end -0.12065 -0.305054)
			(stroke
				(width 0.1)
				(type default)
			)
			(layer "F.Fab")
		)
		(fp_line
			(start 0.67945 -0.3048)
			(end 0.67945 0.3048)
			(stroke
				(width 0.1)
				(type default)
			)
			(layer "F.Fab")
		)
		(fp_line
			(start 0.12065 -0.3048)
			(end 0.67945 -0.3048)
			(stroke
				(width 0.1)
				(type default)
			)
			(layer "F.Fab")
		)
		(fp_line
			(start 0.12065 -0.2794)
			(end 0.12065 -0.3048)
			(stroke
				(width 0.1)
				(type default)
			)
			(layer "F.Fab")
		)
		(fp_line
			(start -0.12065 -0.2794)
			(end 0.12065 -0.2794)
			(stroke
				(width 0.1)
				(type default)
			)
			(layer "F.Fab")
		)
		(fp_line
			(start 0.120396 0.2794)
			(end -0.12065 0.2794)
			(stroke
				(width 0.1)
				(type default)
			)
			(layer "F.Fab")
		)
		(fp_line
			(start -0.12065 0.2794)
			(end -0.12065 0.3048)
			(stroke
				(width 0.1)
				(type default)
			)
			(layer "F.Fab")
		)
		(fp_line
			(start 0.67945 0.3048)
			(end 0.120396 0.3048)
			(stroke
				(width 0.1)
				(type default)
			)
			(layer "F.Fab")
		)
		(fp_line
			(start 0.120396 0.3048)
			(end 0.120396 0.2794)
			(stroke
				(width 0.1)
				(type default)
			)
			(layer "F.Fab")
		)
		(fp_line
			(start -0.12065 0.3048)
			(end -0.67945 0.3048)
			(stroke
				(width 0.1)
				(type default)
			)
			(layer "F.Fab")
		)
		(fp_line
			(start -0.67945 0.3048)
			(end -0.67945 -0.305054)
			(stroke
				(width 0.1)
				(type default)
			)
			(layer "F.Fab")
		)
		(pad "1" smd circle
			(at -0.40005 0 90)
			(size 0 0)
			(layers "F.Cu" "F.Mask" "F.Paste")
			(net "ESPI_CPU0_CS1_R_N")
		)
		(pad "2" smd circle
			(at 0.40005 0 90)
			(size 0 0)
			(layers "F.Cu" "F.Mask" "F.Paste")
			(net "ESPI_CPU0_CS1_N")
		)
	)
	(footprint ""
		(layer "F.Cu")
		(at 96.0628 -418.846 180)
		(property "Reference" "R1455"
			(at 0 0 180)
			(layer "F.SilkS")
			(hide yes)
			(effects
				(font
					(size 1.27 1.27)
				)
			)
		)
		(property "Value" ""
			(at 0 0 180)
			(layer "F.Fab")
			(effects
				(font
					(size 1.27 1.27)
				)
			)
		)
		(duplicate_pad_numbers_are_jumpers no)
		(fp_line
			(start 0.32512 0.175006)
			(end -0.32512 0.175006)
			(stroke
				(width 0.1)
				(type default)
			)
			(layer "F.Fab")
		)
		(fp_line
			(start 0.32512 -0.175006)
			(end 0.32512 0.175006)
			(stroke
				(width 0.1)
				(type default)
			)
			(layer "F.Fab")
		)
		(fp_line
			(start -0.32512 0.175006)
			(end -0.32512 -0.175006)
			(stroke
				(width 0.1)
				(type default)
			)
			(layer "F.Fab")
		)
		(fp_line
			(start -0.32512 -0.175006)
			(end 0.32512 -0.175006)
			(stroke
				(width 0.1)
				(type default)
			)
			(layer "F.Fab")
		)
		(pad "1" smd rect
			(at -0.2667 0 180)
			(size 0.3048 0.381)
			(layers "F.Cu" "F.Mask" "F.Paste")
			(net "P1V8_CPU1_RT_1D")
		)
		(pad "2" smd rect
			(at 0.2667 0)
			(size 0.3048 0.381)
			(layers "F.Cu" "F.Mask" "F.Paste")
			(net "JTAG_TMS_RT_CPU1_P1")
		)
	)
)
